FILE_TYPE = MACRO_DRAWING;
SET COLOR_WIRE YELLOW;
SET COLOR_PROP MONO;
SET COLOR_DOT WHITE;
SET COLOR_ARC YELLOW;
SET COLOR_BODY GREEN;
SET COLOR_NOTE MONO;
SET PROP_DISPLAY VALUE;
SET PAGE_NUMBER P14;
FORCEADD INTEL_CORP_BPAGE..1
(3000 100);
FORCEPROP 1 LAST CDS_CON_LAST_MODIFIED Fri Jun 16 17:48:01 2017
J 0
(1575 425);
PAINT ORANGE (1575 425);
DISPLAY INVISIBLE (1575 425);
FORCEPROP 1 LAST CUSTOM_TXT_CDS <CURRENT_DESIGN_SHEET> OF <TOTAL_DESIGN_SHEETS>
J 0
(2500 125);
PAINT ORANGE (2500 125);
FORCEPROP 1 LAST CUSTOM_TXT_CDS <CON_LAST_MODIFIED>
J 0
(-1000 200);
PAINT ORANGE (-1000 200);
FORCEPROP 2 LAST CUSTOM_TXT_CDS <XR_PAGE_TITLE>
J 0
(-4890 5350);
DISPLAY 0.638298 (-4890 5350);
PAINT PINK (-4890 5350);
DISPLAY INVISIBLE (-4890 5350);
FORCEPROP 1 LAST SCH_TITLE MCP JTAG BLOCK DIAGRAM
J 0
(-4950 150);
DISPLAY 1.212766 (-4950 150);
PAINT ORANGE (-4950 150);
FORCEPROP 2 LAST CDS_LIB mstr_symbols
J 0
(3000 100);
PAINT MONO (3000 100);
DISPLAY INVISIBLE (3000 100);
FORCEPROP 2 LAST PAGE_BORDER TRUE
J 0
(-4890 5350);
DISPLAY 0.638298 (-4890 5350);
PAINT PINK (-4890 5350);
DISPLAY INVISIBLE (-4890 5350);
FORCEPROP 1 LAST COMMENT_BODY TRUE
J 0
(3012 112);
DISPLAY 0.468085 (3012 112);
PAINT GREEN (3012 112);
DISPLAY INVISIBLE (3012 112);
FORCEPROP 2 LAST CDS_XR_PAGE_TITLE CR-14 : @BASEBOARD_FAB2_LIB.BASEBOARD_FAB2(SCH_1):PAGE14
J 0
(-4890 5350);
DISPLAY 0.638298 (-4890 5350);
PAINT PINK (-4890 5350);
DISPLAY INVISIBLE (-4890 5350);
FORCENOTE
$CDS_IMAGE|14_MCP_JTAG_Topology.jpg|5121|5034
(-1800 2875) 0;
DISPLAY LEFT (-1800 2875);
QUIT
